FILE_TYPE = CONNECTIVITY;
{Allegro Design Entry HDL 17.2-2016 S066 (3851973) 4/6/2020}
"PAGE_NUMBER" = 4;
0"NC";
END.
